G04 ================== begin FILE IDENTIFICATION RECORD ==================*
G04 Layout Name:  F:/<user>/2022/FB/R4006-TIMING/brd/gerber-3/R4006-B0001-02_R01.brd*
G04 Film Name:    R4006-B0001-02_R01_BPM*
G04 File Format:  Gerber RS274X*
G04 File Origin:  Cadence Allegro 17.2-S079*
G04 Origin Date:  Fri Feb 25 18:14:43 2022*
G04 *
G04 Layer:  PACKAGE GEOMETRY/SOLDERPASTE_BOTTOM*
G04 Layer:  PACKAGE GEOMETRY/PASTEMASK_BOTTOM*
G04 Layer:  PIN/PASTEMASK_BOTTOM*
G04 Layer:  VIA CLASS/PASTEMASK_BOTTOM*
G04 Layer:  MANUFACTURING/CELESTICA_LEGEND*
G04 Layer:  MANUFACTURING/SOLDERPASTE_BOTTOM*
G04 *
G04 Offset:    (0.00 0.00)*
G04 Mirror:    No*
G04 Mode:      Positive*
G04 Rotation:  0*
G04 FullContactRelief:  No*
G04 UndefLineWidth:     6.00*
G04 ================== end FILE IDENTIFICATION RECORD ====================*
%FSLAX55Y55*MOIN*%
%IR0*IPPOS*OFA0.00000B0.00000*MIA0B0*SFA1.00000B1.00000*%
%ADD23R,.045X.104*%
%ADD26R,.024X.005*%
%ADD15R,.005X.024*%
%ADD22C,.025*%
%ADD24R,.108X.085*%
%ADD25R,.015X.012*%
%ADD13R,.034X.03*%
%ADD14R,.03X.034*%
%ADD16R,.065X.02*%
%ADD19R,.02X.047*%
%ADD12R,.06X.018*%
%ADD18R,.013X.038*%
%ADD11R,.024X.028*%
%ADD10R,.028X.024*%
%ADD28R,.043X.057*%
%ADD20R,.054X.038*%
%ADD17R,.038X.054*%
%ADD21R,.055X.039*%
%ADD27R,.039X.057*%
%ADD29C,.01*%
%ADD30C,.005*%
%ADD31C,.006*%
G75*
%LPD*%
G75*
G36*
G01X163800Y404300D02*
Y401900D01*
X162400D01*
Y404300D01*
X163800D01*
G37*
G36*
G01X336100Y393500D02*
Y395900D01*
X337500D01*
Y393500D01*
X336100D01*
G37*
G36*
G01X562800Y216300D02*
Y217700D01*
X565200D01*
Y216300D01*
X562800D01*
G37*
G54D10*
X24100Y297500D03*
X19900D03*
Y302500D03*
X24100D03*
Y292500D03*
X19900D03*
Y287500D03*
X24100D03*
Y307500D03*
X19900D03*
X63500Y61500D03*
X67700D03*
X80900Y66500D03*
X71700Y154400D03*
X67500D03*
X80800Y163900D03*
Y159400D03*
X80400Y150000D03*
X71600Y149500D03*
X67400D03*
X80800Y154900D03*
X71800Y159900D03*
X67600D03*
X80800Y168400D03*
X69900Y291500D03*
X74100D03*
X74600Y320000D03*
X70400D03*
Y315500D03*
X74600D03*
Y324500D03*
X70400D03*
X88900Y71000D03*
X84700D03*
X85100Y66500D03*
X85000Y163900D03*
Y159400D03*
X84600Y150000D03*
X85000Y154900D03*
Y168400D03*
X91100Y345500D03*
X86900D03*
X91100Y350000D03*
X86900D03*
X91100Y341000D03*
X86900D03*
X103800Y71800D03*
X108000D03*
X115400Y347500D03*
X130900Y75300D03*
X117370Y70860D03*
X121570D03*
X121580Y65870D03*
X117380D03*
X130850Y65800D03*
X130870Y70800D03*
X133400Y350000D03*
X119600Y347500D03*
X135100Y75300D03*
X135050Y65800D03*
X135070Y70800D03*
X147900Y300000D03*
X138100Y328000D03*
X133900D03*
X138100Y323500D03*
X133900D03*
X137600Y350000D03*
X147700Y390100D03*
X143500D03*
X146700Y385100D03*
X142500D03*
X147700Y403600D03*
X143500D03*
Y394600D03*
X147700D03*
X143500Y399100D03*
X147700D03*
X143500Y414200D03*
X147700D03*
X152100Y300000D03*
X154000Y377600D03*
X158200D03*
X166600Y388500D03*
X162400D03*
X176600Y391000D03*
X172400D03*
X210400Y336000D03*
X214600D03*
X210400Y355000D03*
X214600D03*
X210400Y350000D03*
X214600D03*
X241900Y235500D03*
X246100D03*
X255100Y237500D03*
X250900D03*
X259900D03*
X264100D03*
X283850Y194500D03*
X279650D03*
X304100Y205000D03*
X299900D03*
X304100Y200500D03*
X299900D03*
X306800Y321000D03*
X302600D03*
Y330500D03*
X306800D03*
X302600Y335000D03*
X306800D03*
Y326000D03*
X302600D03*
X324400Y407000D03*
X341900Y225500D03*
X332900D03*
X337100D03*
Y221000D03*
X332900D03*
X341900D03*
X329800Y320500D03*
X325600D03*
X329800Y329500D03*
X325600D03*
X329800Y334000D03*
X325600D03*
X329800Y338500D03*
X325600D03*
X329800Y325000D03*
X325600D03*
X329800Y347500D03*
X325600D03*
X329800Y343000D03*
X325600D03*
X328600Y407000D03*
X334400Y409500D03*
X338600D03*
X357500Y193149D03*
X353300D03*
X357500Y188649D03*
X353300D03*
X346100Y225500D03*
Y221000D03*
X350600Y337000D03*
X346400D03*
X350600Y332500D03*
X346400D03*
X350600Y328000D03*
X346400D03*
X350600Y323500D03*
X346400D03*
X350600Y341500D03*
X346400D03*
X352200Y394200D03*
X356400D03*
Y403200D03*
X352200D03*
Y407700D03*
X356400D03*
Y398700D03*
X352200D03*
X359400Y419700D03*
X355200D03*
X353900Y413000D03*
X358100D03*
X374600Y172000D03*
X370400D03*
X365100Y217000D03*
X360900D03*
X374400Y323500D03*
Y328000D03*
Y332500D03*
Y337000D03*
Y341500D03*
X387629Y129361D03*
X391829D03*
X384430Y174500D03*
X388630D03*
X383500Y309200D03*
X379300D03*
X393300D03*
X389100D03*
X378600Y323500D03*
Y328000D03*
Y332500D03*
Y337000D03*
Y341500D03*
X383900Y375800D03*
X388100D03*
X383900Y381000D03*
X388100D03*
X409800Y175000D03*
X402400Y221500D03*
X406600D03*
X401500Y323900D03*
X397300D03*
X401500Y329100D03*
X397300D03*
X426900Y73000D03*
X414000Y175000D03*
X419900D03*
X424100D03*
X426600Y406500D03*
X422400D03*
X426600Y411500D03*
X422400D03*
X431100Y73000D03*
X432300Y174100D03*
X436500D03*
X446511Y175500D03*
X442311D03*
X445485Y222000D03*
X436600Y297500D03*
X432400D03*
X435400Y386500D03*
X439600D03*
Y396500D03*
X435400D03*
Y406500D03*
X439600D03*
X435400Y411500D03*
X439600D03*
X455511Y175500D03*
X451311D03*
X463900D03*
X449685Y222000D03*
X456600Y284500D03*
X452400D03*
Y279500D03*
X456600D03*
Y289500D03*
X452400D03*
Y294500D03*
X456600D03*
X461400Y389500D03*
Y394000D03*
X473600Y91500D03*
X469400D03*
X473600Y96500D03*
X469400D03*
X468100Y175500D03*
X473600Y355100D03*
X477800D03*
X465600Y389500D03*
Y394000D03*
X488400Y163000D03*
X492600D03*
Y167500D03*
X488400D03*
X492600Y176500D03*
X488400D03*
Y181000D03*
X492600D03*
X488400Y197500D03*
X492600D03*
X488400Y185500D03*
X492600D03*
Y202500D03*
X488400D03*
X498900Y345500D03*
X503100D03*
X544600Y69000D03*
X540400D03*
Y64000D03*
X544600D03*
X543100Y227500D03*
X538900D03*
X550400Y264000D03*
Y259500D03*
X550200Y272100D03*
X550400Y277000D03*
Y281500D03*
X550200Y292250D03*
X550400Y302000D03*
X549600Y287000D03*
X545400D03*
X550400Y306500D03*
X563100Y198000D03*
X558900D03*
X554600Y264000D03*
Y259500D03*
X554400Y272100D03*
X554600Y277000D03*
Y281500D03*
X554400Y292250D03*
X554600Y302000D03*
Y306500D03*
X552900Y407000D03*
X557100D03*
Y411500D03*
X552900D03*
X576200Y390700D03*
X572000D03*
X576200Y385700D03*
X572000D03*
X576900Y407500D03*
X581100D03*
Y412000D03*
X576900D03*
X599400Y261500D03*
X603600D03*
X599400Y279000D03*
X603600D03*
X637900Y96500D03*
Y102000D03*
Y108000D03*
X642100Y96500D03*
Y102000D03*
Y108000D03*
G54D20*
X285000Y227700D03*
Y234300D03*
X296000Y284700D03*
X303500D03*
X296000Y291300D03*
X303500D03*
X311000Y284700D03*
Y291300D03*
X318500Y375700D03*
Y382300D03*
X346000Y131200D03*
Y137800D03*
X378500Y130200D03*
Y136800D03*
X366200Y295200D03*
Y301800D03*
X540000Y178700D03*
Y185300D03*
G54D11*
X33500Y282900D03*
X29000D03*
X33500Y287100D03*
X29000D03*
X57700Y65500D03*
Y69700D03*
X53000D03*
Y65500D03*
X53500Y88400D03*
Y92600D03*
X53000Y144400D03*
Y148600D03*
Y204900D03*
Y209100D03*
Y258400D03*
Y262600D03*
X79900Y71100D03*
Y75300D03*
X72100Y81700D03*
Y85900D03*
X74300Y95300D03*
Y91100D03*
X78800Y95300D03*
Y91100D03*
X69800D03*
Y95300D03*
X76000Y240200D03*
Y244400D03*
X80500Y240200D03*
Y244400D03*
X71500D03*
Y240200D03*
X66000Y301400D03*
Y305600D03*
X70000Y338400D03*
Y342600D03*
X86000Y83300D03*
Y79100D03*
X87800Y91100D03*
Y95300D03*
X83300Y91100D03*
Y95300D03*
X89600Y244400D03*
Y240200D03*
X85000Y244400D03*
Y240200D03*
X90800Y278900D03*
Y283100D03*
X85800D03*
Y278900D03*
X95000Y356400D03*
X88200Y355300D03*
X95000Y360600D03*
X88200Y359500D03*
X103500Y309400D03*
Y313600D03*
X113000Y356400D03*
X99500D03*
X104000D03*
X108500D03*
X113000Y360600D03*
X105500Y368900D03*
Y373100D03*
X99500Y360600D03*
X104000D03*
X108500D03*
X128000Y309400D03*
Y313600D03*
X126500Y356400D03*
X117500D03*
X122000D03*
X126500Y360600D03*
X117500D03*
X122000D03*
X137500Y355900D03*
Y360100D03*
X163000Y350400D03*
Y354600D03*
X180000Y406600D03*
Y402400D03*
X186460Y60220D03*
Y64420D03*
X188500Y298100D03*
Y293900D03*
X215500Y65600D03*
Y61400D03*
X220000Y65600D03*
Y61400D03*
X217300Y293100D03*
Y297300D03*
X212800Y293100D03*
Y297300D03*
X208300Y293100D03*
Y297300D03*
X210500Y340900D03*
Y345100D03*
X234310Y58390D03*
Y62590D03*
X239311Y58400D03*
X246122D03*
X251122D03*
X239311Y62600D03*
X246122D03*
X251122D03*
X254000Y230600D03*
Y226400D03*
Y217400D03*
Y221600D03*
X265807Y58400D03*
X270807D03*
X265807Y62600D03*
X270807D03*
X259000Y226400D03*
Y230600D03*
X280055Y58400D03*
X285055D03*
X280055Y62600D03*
X285055D03*
X279500Y188000D03*
Y183800D03*
X279000Y216400D03*
Y229600D03*
Y233800D03*
Y220600D03*
X290000Y284400D03*
X285500D03*
X290000Y288600D03*
X285500D03*
X297303Y58400D03*
X302303D03*
X297303Y62600D03*
X302303D03*
X291000Y229900D03*
Y234100D03*
X324500Y285900D03*
Y290100D03*
X318500Y387900D03*
Y392100D03*
X333500Y251100D03*
Y255300D03*
X335000Y286400D03*
X339500D03*
X335000Y290600D03*
X339500D03*
X352000Y133400D03*
Y137600D03*
X350500Y178900D03*
Y183100D03*
X347000Y233400D03*
Y237600D03*
X344000Y286400D03*
X348500D03*
X344000Y290600D03*
X348500D03*
X377000Y76900D03*
Y81100D03*
X391900Y251000D03*
X386000D03*
X380100D03*
X391900Y255200D03*
X386000D03*
X380100D03*
X403700Y251000D03*
X397800D03*
X409300D03*
X403700Y255200D03*
X397800D03*
X409300D03*
X398000Y347100D03*
Y342900D03*
X427500Y91900D03*
Y96100D03*
X420900Y251000D03*
X415000D03*
X420900Y255200D03*
X415000D03*
X417000Y347100D03*
Y342900D03*
X424000Y398300D03*
Y394100D03*
X432000Y91900D03*
Y96100D03*
X441500Y107900D03*
Y112100D03*
X437000Y107900D03*
Y112100D03*
X430500Y164900D03*
Y159100D03*
Y154900D03*
Y169100D03*
X430600Y179500D03*
Y183700D03*
X430000Y198700D03*
Y202900D03*
X435000Y246100D03*
Y241900D03*
X444000Y246100D03*
Y241900D03*
X439500D03*
Y246100D03*
X453000Y113900D03*
Y118100D03*
X458500Y113900D03*
Y118100D03*
X462000Y241900D03*
Y246100D03*
X457500D03*
Y241900D03*
X448500Y246100D03*
Y241900D03*
X453000D03*
Y246100D03*
X478000Y182111D03*
Y186311D03*
X496100Y268600D03*
Y272800D03*
X488500Y354600D03*
Y350400D03*
X498500Y354600D03*
Y350400D03*
X493500Y354600D03*
Y350400D03*
X508500Y385400D03*
Y389600D03*
X503500Y385400D03*
Y389600D03*
X527800Y265300D03*
Y261100D03*
X527300Y420101D03*
Y415901D03*
X532300D03*
Y420101D03*
X539000Y160400D03*
Y164600D03*
X551000Y202400D03*
Y206600D03*
Y212900D03*
Y217100D03*
Y232400D03*
X546500D03*
X551000Y236600D03*
X546500D03*
X545250Y267950D03*
Y263750D03*
X545200Y277100D03*
Y281300D03*
Y292250D03*
Y296450D03*
Y301900D03*
Y306100D03*
X543500Y416600D03*
Y412400D03*
Y421900D03*
Y426100D03*
X555700Y70500D03*
Y74700D03*
X555500Y65000D03*
Y60800D03*
X560000Y232400D03*
X555500D03*
X560000Y236600D03*
X555500D03*
X567500Y408400D03*
X567000Y421900D03*
Y426100D03*
X555500Y421900D03*
Y426100D03*
X567500Y412600D03*
X582500Y75400D03*
X577500D03*
X577200Y65800D03*
Y70000D03*
X582500Y79600D03*
X577500D03*
X575400Y232400D03*
Y236600D03*
X579000Y421900D03*
Y426100D03*
X598000Y141900D03*
Y146100D03*
Y153900D03*
Y158100D03*
Y163400D03*
Y167600D03*
Y173900D03*
Y178100D03*
X591902Y195065D03*
Y190865D03*
X596902D03*
Y195065D03*
X601902Y190865D03*
Y195065D03*
X602500Y408900D03*
X591000D03*
X602700Y421900D03*
Y426100D03*
X602500Y413100D03*
X591000D03*
X617000Y147600D03*
Y143400D03*
Y157600D03*
Y153400D03*
Y163400D03*
Y167600D03*
X615500Y176900D03*
Y181100D03*
X606902Y190865D03*
Y195065D03*
X621000Y196774D03*
Y200974D03*
X614000Y421900D03*
Y426100D03*
X614500Y409400D03*
Y413600D03*
X625500Y196774D03*
X630000D03*
X625500Y200974D03*
X630000D03*
G54D30*
G01X329433Y-125500D02*
Y-133000D01*
X333167D01*
G01X340480D02*
Y-128000D01*
G01Y-128875D02*
X340107Y-128375D01*
X339547Y-128125D01*
X338893Y-128000D01*
X338240Y-128250D01*
X337680Y-128750D01*
X337307Y-129500D01*
X337120Y-130500D01*
X337307Y-131500D01*
X337680Y-132250D01*
X338240Y-132750D01*
X338893Y-133000D01*
X339547Y-132875D01*
X340107Y-132500D01*
X340480Y-132000D01*
G01X344340Y-135250D02*
X344900Y-135500D01*
X345647Y-135250D01*
X346113Y-134750D01*
X346487Y-134125D01*
X347047Y-132125D01*
X348260Y-128000D01*
G01X345273D02*
X347047Y-132125D01*
G01X352400Y-129625D02*
X355387D01*
X355107Y-128750D01*
X354640Y-128250D01*
X353987Y-128000D01*
X353333Y-128125D01*
X352773Y-128500D01*
X352400Y-129375D01*
X352213Y-130125D01*
Y-130875D01*
X352400Y-131625D01*
X352867Y-132375D01*
X353427Y-132875D01*
X354080Y-133000D01*
X354733Y-132750D01*
X355387Y-132000D01*
G01X359993Y-133000D02*
Y-128000D01*
G01Y-129000D02*
X360460Y-128500D01*
X360927Y-128125D01*
X361580Y-128000D01*
X362047Y-128125D01*
X362607Y-128500D01*
G01X368800Y-133250D02*
X368613Y-133125D01*
Y-132875D01*
X368800Y-132750D01*
X368987Y-132875D01*
Y-133125D01*
X368800Y-133250D01*
G01Y-129875D02*
X368613Y-129750D01*
Y-129500D01*
X368800Y-129375D01*
X368987Y-129500D01*
Y-129750D01*
X368800Y-129875D01*
G01X336747Y-120500D02*
Y-113000D01*
X338613D01*
X339360Y-113375D01*
X339920Y-113875D01*
X340387Y-114625D01*
X340760Y-115500D01*
X340853Y-116750D01*
X340760Y-118000D01*
X340387Y-118875D01*
X339920Y-119625D01*
X339360Y-120125D01*
X338613Y-120500D01*
X336747D01*
G01X347980D02*
Y-115500D01*
G01Y-116375D02*
X347607Y-115875D01*
X347047Y-115625D01*
X346393Y-115500D01*
X345740Y-115750D01*
X345180Y-116250D01*
X344807Y-117000D01*
X344620Y-118000D01*
X344807Y-119000D01*
X345180Y-119750D01*
X345740Y-120250D01*
X346393Y-120500D01*
X347047Y-120375D01*
X347607Y-120000D01*
X347980Y-119500D01*
G01X353800Y-113000D02*
Y-120500D01*
G01X352493Y-115500D02*
X355107D01*
G01X359900Y-117125D02*
X362887D01*
X362607Y-116250D01*
X362140Y-115750D01*
X361487Y-115500D01*
X360833Y-115625D01*
X360273Y-116000D01*
X359900Y-116875D01*
X359713Y-117625D01*
Y-118375D01*
X359900Y-119125D01*
X360367Y-119875D01*
X360927Y-120375D01*
X361580Y-120500D01*
X362233Y-120250D01*
X362887Y-119500D01*
G01X368800Y-120750D02*
X368613Y-120625D01*
Y-120375D01*
X368800Y-120250D01*
X368987Y-120375D01*
Y-120625D01*
X368800Y-120750D01*
G01Y-117375D02*
X368613Y-117250D01*
Y-117000D01*
X368800Y-116875D01*
X368987Y-117000D01*
Y-117250D01*
X368800Y-117375D01*
G01X382027Y-114250D02*
X382587Y-113500D01*
X383240Y-113125D01*
X383987Y-113000D01*
X384920Y-113250D01*
X385573Y-113875D01*
X385760Y-114625D01*
X385667Y-115375D01*
X385293Y-116000D01*
X383427Y-117250D01*
X382587Y-118125D01*
X382027Y-119375D01*
X381840Y-120500D01*
X385760D01*
G01X391300Y-113000D02*
X390553Y-113250D01*
X389993Y-113875D01*
X389620Y-114625D01*
X389340Y-115625D01*
X389247Y-116750D01*
X389340Y-117875D01*
X389620Y-118875D01*
X389993Y-119625D01*
X390553Y-120250D01*
X391300Y-120500D01*
X392047Y-120250D01*
X392607Y-119625D01*
X392980Y-118875D01*
X393260Y-117875D01*
X393353Y-116750D01*
X393260Y-115625D01*
X392980Y-114625D01*
X392607Y-113875D01*
X392047Y-113250D01*
X391300Y-113000D01*
G01X397027Y-114250D02*
X397587Y-113500D01*
X398240Y-113125D01*
X398987Y-113000D01*
X399920Y-113250D01*
X400573Y-113875D01*
X400760Y-114625D01*
X400667Y-115375D01*
X400293Y-116000D01*
X398427Y-117250D01*
X397587Y-118125D01*
X397027Y-119375D01*
X396840Y-120500D01*
X400760D01*
G01X404527Y-114250D02*
X405087Y-113500D01*
X405740Y-113125D01*
X406487Y-113000D01*
X407420Y-113250D01*
X408073Y-113875D01*
X408260Y-114625D01*
X408167Y-115375D01*
X407793Y-116000D01*
X405927Y-117250D01*
X405087Y-118125D01*
X404527Y-119375D01*
X404340Y-120500D01*
X408260D01*
G01X412587Y-118000D02*
X415013D01*
G01X421300Y-113000D02*
X420553Y-113250D01*
X419993Y-113875D01*
X419620Y-114625D01*
X419340Y-115625D01*
X419247Y-116750D01*
X419340Y-117875D01*
X419620Y-118875D01*
X419993Y-119625D01*
X420553Y-120250D01*
X421300Y-120500D01*
X422047Y-120250D01*
X422607Y-119625D01*
X422980Y-118875D01*
X423260Y-117875D01*
X423353Y-116750D01*
X423260Y-115625D01*
X422980Y-114625D01*
X422607Y-113875D01*
X422047Y-113250D01*
X421300Y-113000D01*
G01X427027Y-114250D02*
X427587Y-113500D01*
X428240Y-113125D01*
X428987Y-113000D01*
X429920Y-113250D01*
X430573Y-113875D01*
X430760Y-114625D01*
X430667Y-115375D01*
X430293Y-116000D01*
X428427Y-117250D01*
X427587Y-118125D01*
X427027Y-119375D01*
X426840Y-120500D01*
X430760D01*
G01X435087Y-118000D02*
X437513D01*
G01X442027Y-114250D02*
X442587Y-113500D01*
X443240Y-113125D01*
X443987Y-113000D01*
X444920Y-113250D01*
X445573Y-113875D01*
X445760Y-114625D01*
X445667Y-115375D01*
X445293Y-116000D01*
X443427Y-117250D01*
X442587Y-118125D01*
X442027Y-119375D01*
X441840Y-120500D01*
X445760D01*
G01X449247Y-119375D02*
X449807Y-120000D01*
X450460Y-120375D01*
X451300Y-120500D01*
X452140Y-120250D01*
X452793Y-119750D01*
X453260Y-118875D01*
X453353Y-117875D01*
X453167Y-116875D01*
X452700Y-116250D01*
X452047Y-115750D01*
X451393Y-115625D01*
X450740Y-115750D01*
X449900Y-116250D01*
X450180Y-113000D01*
X452700D01*
G01X336933Y-108000D02*
Y-100500D01*
X339267D01*
X340013Y-100875D01*
X340480Y-101375D01*
X340667Y-102375D01*
X340480Y-103375D01*
X339920Y-104000D01*
X339267Y-104375D01*
X336933D01*
G01X339267D02*
X340667Y-108000D01*
G01X344900Y-104625D02*
X347887D01*
X347607Y-103750D01*
X347140Y-103250D01*
X346487Y-103000D01*
X345833Y-103125D01*
X345273Y-103500D01*
X344900Y-104375D01*
X344713Y-105125D01*
Y-105875D01*
X344900Y-106625D01*
X345367Y-107375D01*
X345927Y-107875D01*
X346580Y-108000D01*
X347233Y-107750D01*
X347887Y-107000D01*
G01X352120Y-103000D02*
X353800Y-108000D01*
X355480Y-103000D01*
G01X368800Y-108250D02*
X368613Y-108125D01*
Y-107875D01*
X368800Y-107750D01*
X368987Y-107875D01*
Y-108125D01*
X368800Y-108250D01*
G01Y-104875D02*
X368613Y-104750D01*
Y-104500D01*
X368800Y-104375D01*
X368987Y-104500D01*
Y-104750D01*
X368800Y-104875D01*
G01X383800Y-100500D02*
X383053Y-100750D01*
X382493Y-101375D01*
X382120Y-102125D01*
X381840Y-103125D01*
X381747Y-104250D01*
X381840Y-105375D01*
X382120Y-106375D01*
X382493Y-107125D01*
X383053Y-107750D01*
X383800Y-108000D01*
X384547Y-107750D01*
X385107Y-107125D01*
X385480Y-106375D01*
X385760Y-105375D01*
X385853Y-104250D01*
X385760Y-103125D01*
X385480Y-102125D01*
X385107Y-101375D01*
X384547Y-100750D01*
X383800Y-100500D01*
G01X391300Y-108000D02*
Y-100500D01*
X390180Y-102000D01*
G01Y-108000D02*
X392420D01*
G01X336933Y-95500D02*
Y-88000D01*
X339173D01*
X339920Y-88375D01*
X340480Y-89250D01*
X340667Y-90250D01*
X340480Y-91250D01*
X340013Y-92000D01*
X339173Y-92375D01*
X336933D01*
G01X344620Y-95750D02*
X347980Y-88000D01*
G01X351653Y-95500D02*
Y-88000D01*
X355947Y-95500D01*
Y-88000D01*
G01X368800Y-95750D02*
X368613Y-95625D01*
Y-95375D01*
X368800Y-95250D01*
X368987Y-95375D01*
Y-95625D01*
X368800Y-95750D01*
G01Y-92375D02*
X368613Y-92250D01*
Y-92000D01*
X368800Y-91875D01*
X368987Y-92000D01*
Y-92250D01*
X368800Y-92375D01*
G01X381933Y-95500D02*
Y-88000D01*
X384267D01*
X385013Y-88375D01*
X385480Y-88875D01*
X385667Y-89875D01*
X385480Y-90875D01*
X384920Y-91500D01*
X384267Y-91875D01*
X381933D01*
G01X384267D02*
X385667Y-95500D01*
G01X392420D02*
Y-88000D01*
X388967Y-93375D01*
X393633D01*
G01X398800Y-88000D02*
X398053Y-88250D01*
X397493Y-88875D01*
X397120Y-89625D01*
X396840Y-90625D01*
X396747Y-91750D01*
X396840Y-92875D01*
X397120Y-93875D01*
X397493Y-94625D01*
X398053Y-95250D01*
X398800Y-95500D01*
X399547Y-95250D01*
X400107Y-94625D01*
X400480Y-93875D01*
X400760Y-92875D01*
X400853Y-91750D01*
X400760Y-90625D01*
X400480Y-89625D01*
X400107Y-88875D01*
X399547Y-88250D01*
X398800Y-88000D01*
G01X406300D02*
X405553Y-88250D01*
X404993Y-88875D01*
X404620Y-89625D01*
X404340Y-90625D01*
X404247Y-91750D01*
X404340Y-92875D01*
X404620Y-93875D01*
X404993Y-94625D01*
X405553Y-95250D01*
X406300Y-95500D01*
X407047Y-95250D01*
X407607Y-94625D01*
X407980Y-93875D01*
X408260Y-92875D01*
X408353Y-91750D01*
X408260Y-90625D01*
X407980Y-89625D01*
X407607Y-88875D01*
X407047Y-88250D01*
X406300Y-88000D01*
G01X412027Y-92375D02*
X412680Y-91500D01*
X413240Y-91000D01*
X413987Y-90750D01*
X414640Y-91000D01*
X415107Y-91500D01*
X415480Y-92250D01*
X415573Y-93125D01*
X415480Y-93875D01*
X415107Y-94625D01*
X414547Y-95250D01*
X413893Y-95500D01*
X413147Y-95250D01*
X412493Y-94500D01*
X412120Y-93375D01*
X412027Y-92125D01*
X412213Y-90500D01*
X412493Y-89625D01*
X412960Y-88750D01*
X413613Y-88125D01*
X414267Y-88000D01*
X414920Y-88250D01*
X415387Y-88875D01*
G01X420087Y-93000D02*
X422513D01*
G01X429547Y-91500D02*
X429920Y-91125D01*
X430200Y-90500D01*
X430387Y-89625D01*
X430200Y-88875D01*
X429827Y-88375D01*
X429173Y-88000D01*
X426653D01*
Y-95500D01*
X429733D01*
X430387Y-95000D01*
X430760Y-94250D01*
X430947Y-93375D01*
X430760Y-92500D01*
X430200Y-91750D01*
X429547Y-91500D01*
X426653D01*
G01X436300Y-88000D02*
X435553Y-88250D01*
X434993Y-88875D01*
X434620Y-89625D01*
X434340Y-90625D01*
X434247Y-91750D01*
X434340Y-92875D01*
X434620Y-93875D01*
X434993Y-94625D01*
X435553Y-95250D01*
X436300Y-95500D01*
X437047Y-95250D01*
X437607Y-94625D01*
X437980Y-93875D01*
X438260Y-92875D01*
X438353Y-91750D01*
X438260Y-90625D01*
X437980Y-89625D01*
X437607Y-88875D01*
X437047Y-88250D01*
X436300Y-88000D01*
G01X443800D02*
X443053Y-88250D01*
X442493Y-88875D01*
X442120Y-89625D01*
X441840Y-90625D01*
X441747Y-91750D01*
X441840Y-92875D01*
X442120Y-93875D01*
X442493Y-94625D01*
X443053Y-95250D01*
X443800Y-95500D01*
X444547Y-95250D01*
X445107Y-94625D01*
X445480Y-93875D01*
X445760Y-92875D01*
X445853Y-91750D01*
X445760Y-90625D01*
X445480Y-89625D01*
X445107Y-88875D01*
X444547Y-88250D01*
X443800Y-88000D01*
G01X451300D02*
X450553Y-88250D01*
X449993Y-88875D01*
X449620Y-89625D01*
X449340Y-90625D01*
X449247Y-91750D01*
X449340Y-92875D01*
X449620Y-93875D01*
X449993Y-94625D01*
X450553Y-95250D01*
X451300Y-95500D01*
X452047Y-95250D01*
X452607Y-94625D01*
X452980Y-93875D01*
X453260Y-92875D01*
X453353Y-91750D01*
X453260Y-90625D01*
X452980Y-89625D01*
X452607Y-88875D01*
X452047Y-88250D01*
X451300Y-88000D01*
G01X458800Y-95500D02*
Y-88000D01*
X457680Y-89500D01*
G01Y-95500D02*
X459920D01*
G01X465087Y-93000D02*
X467513D01*
G01X473800Y-88000D02*
X473053Y-88250D01*
X472493Y-88875D01*
X472120Y-89625D01*
X471840Y-90625D01*
X471747Y-91750D01*
X471840Y-92875D01*
X472120Y-93875D01*
X472493Y-94625D01*
X473053Y-95250D01*
X473800Y-95500D01*
X474547Y-95250D01*
X475107Y-94625D01*
X475480Y-93875D01*
X475760Y-92875D01*
X475853Y-91750D01*
X475760Y-90625D01*
X475480Y-89625D01*
X475107Y-88875D01*
X474547Y-88250D01*
X473800Y-88000D01*
G01X479527Y-89250D02*
X480087Y-88500D01*
X480740Y-88125D01*
X481487Y-88000D01*
X482420Y-88250D01*
X483073Y-88875D01*
X483260Y-89625D01*
X483167Y-90375D01*
X482793Y-91000D01*
X480927Y-92250D01*
X480087Y-93125D01*
X479527Y-94375D01*
X479340Y-95500D01*
X483260D01*
G01X382381Y-131929D02*
X383128Y-132554D01*
X383968Y-132929D01*
X384714D01*
X385461Y-132554D01*
X386021Y-131929D01*
X386301Y-131054D01*
X386114Y-130179D01*
X385648Y-129429D01*
X384808Y-128929D01*
X383688Y-128679D01*
X383034Y-128179D01*
X382754Y-127304D01*
X382941Y-126429D01*
X383408Y-125804D01*
X384061Y-125429D01*
X384714D01*
X385368Y-125679D01*
X385928Y-126304D01*
G01X391841Y-132929D02*
X391094Y-132804D01*
X390441Y-132304D01*
X389881Y-131554D01*
X389508Y-130679D01*
X389321Y-129679D01*
Y-128679D01*
X389508Y-127679D01*
X389881Y-126804D01*
X390441Y-126054D01*
X391094Y-125554D01*
X391841Y-125429D01*
X392588Y-125554D01*
X393241Y-126054D01*
X393801Y-126804D01*
X394174Y-127679D01*
X394361Y-128679D01*
Y-129679D01*
X394174Y-130679D01*
X393801Y-131554D01*
X393241Y-132304D01*
X392588Y-132804D01*
X391841Y-132929D01*
G01X397474Y-125429D02*
Y-132929D01*
X401208D01*
G01X404788D02*
Y-125429D01*
X406654D01*
X407401Y-125804D01*
X407961Y-126304D01*
X408428Y-127054D01*
X408801Y-127929D01*
X408894Y-129179D01*
X408801Y-130429D01*
X408428Y-131304D01*
X407961Y-132054D01*
X407401Y-132554D01*
X406654Y-132929D01*
X404788D01*
G01X416208D02*
X412474D01*
Y-125429D01*
X416208D01*
G01X414714Y-129054D02*
X412474D01*
G01X419974Y-132929D02*
Y-125429D01*
X422308D01*
X423054Y-125804D01*
X423521Y-126304D01*
X423708Y-127304D01*
X423521Y-128304D01*
X422961Y-128929D01*
X422308Y-129304D01*
X419974D01*
G01X422308D02*
X423708Y-132929D01*
G01X427474D02*
Y-125429D01*
X429714D01*
X430461Y-125804D01*
X431021Y-126679D01*
X431208Y-127679D01*
X431021Y-128679D01*
X430554Y-129429D01*
X429714Y-129804D01*
X427474D01*
G01X434508Y-132929D02*
X436841Y-125429D01*
X439174Y-132929D01*
G01X438334Y-130304D02*
X435348D01*
G01X442381Y-131929D02*
X443128Y-132554D01*
X443968Y-132929D01*
X444714D01*
X445461Y-132554D01*
X446021Y-131929D01*
X446301Y-131054D01*
X446114Y-130179D01*
X445648Y-129429D01*
X444808Y-128929D01*
X443688Y-128679D01*
X443034Y-128179D01*
X442754Y-127304D01*
X442941Y-126429D01*
X443408Y-125804D01*
X444061Y-125429D01*
X444714D01*
X445368Y-125679D01*
X445928Y-126304D01*
G01X451841Y-125429D02*
Y-132929D01*
G01X449694Y-125429D02*
X453988D01*
G01X461208Y-132929D02*
X457474D01*
Y-125429D01*
X461208D01*
G01X459714Y-129054D02*
X457474D01*
G01X475088Y-128929D02*
X475461Y-128554D01*
X475741Y-127929D01*
X475928Y-127054D01*
X475741Y-126304D01*
X475368Y-125804D01*
X474714Y-125429D01*
X472194D01*
Y-132929D01*
X475274D01*
X475928Y-132429D01*
X476301Y-131679D01*
X476488Y-130804D01*
X476301Y-129929D01*
X475741Y-129179D01*
X475088Y-128929D01*
X472194D01*
G01X481841Y-132929D02*
X481094Y-132804D01*
X480441Y-132304D01*
X479881Y-131554D01*
X479508Y-130679D01*
X479321Y-129679D01*
Y-128679D01*
X479508Y-127679D01*
X479881Y-126804D01*
X480441Y-126054D01*
X481094Y-125554D01*
X481841Y-125429D01*
X482588Y-125554D01*
X483241Y-126054D01*
X483801Y-126804D01*
X484174Y-127679D01*
X484361Y-128679D01*
Y-129679D01*
X484174Y-130679D01*
X483801Y-131554D01*
X483241Y-132304D01*
X482588Y-132804D01*
X481841Y-132929D01*
G01X489341Y-125429D02*
Y-132929D01*
G01X487194Y-125429D02*
X491488D01*
G54D21*
X305350Y214300D03*
X305850Y231500D03*
X297150Y235200D03*
Y227800D03*
X296650Y218000D03*
X305350Y221700D03*
G54D12*
X36950Y302840D03*
Y295160D03*
Y297720D03*
Y300280D03*
X55050Y295160D03*
Y302840D03*
Y300280D03*
Y297720D03*
G54D31*
G01X145964Y-110118D02*
G03I-634J0D01*
G01X149695D02*
G03I-1038J0D01*
G01X168013Y-137456D02*
G03I-634J0D01*
G01X155900Y-133655D02*
G03I-632J0D01*
G01X161735Y-128639D02*
G03I-1458J0D01*
G01X158530Y-131428D02*
G03I-1041J0D01*
G01X158461Y-119126D02*
G03I-1283J0D01*
G01X162690Y-117490D02*
G03I-1584J0D01*
G01X169809Y-121292D02*
G03I-2180J0D01*
G01X165531Y-125255D02*
G03I-1869J0D01*
G01X167813Y-115513D02*
G03I-1971J0D01*
G01X154775Y-120500D02*
G03I-892J0D01*
G01X162681Y-102774D02*
G03I-1584J0D01*
G01X158451Y-101149D02*
G03I-1283J0D01*
G01X159258Y-110118D02*
G03I-1868J0D01*
G01X169812Y-98951D02*
G03I-2180J0D01*
G01X167802Y-104739D02*
G03I-1971J0D01*
G01X165183Y-110118D02*
G03I-2180J0D01*
G01X171881D02*
G03I-2642J0D01*
G01X152135Y-98681D02*
G03I-632J0D01*
G01X154064Y-110118D02*
G03I-1460J0D01*
G01X154764Y-99775D02*
G03I-892J0D01*
G01X158530Y-88809D02*
G03I-1041J0D01*
G01X161742Y-91601D02*
G03I-1458J0D01*
G01X165531Y-94981D02*
G03I-1869J0D01*
G01X171080Y-131739D02*
G03I-1282J0D01*
G01X169322Y-135033D02*
G03I-892J0D01*
G01X180669Y-131528D02*
G03I-1870J0D01*
G01X180255Y-136311D02*
G03I-1456J0D01*
G01X179841Y-140261D02*
G03I-1042J0D01*
G01X179433Y-143587D02*
G03I-634J0D01*
G01X181439Y-119680D02*
G03I-2640J0D01*
G01X175373Y-123081D02*
G03I-1968J0D01*
G01X173018Y-127816D02*
G03I-1584J0D01*
G01X174681Y-116876D02*
G03I-2640J0D01*
G01X180979Y-125917D02*
G03I-2180J0D01*
G01X186177Y-123075D02*
G03I-1971J0D01*
G01X188199Y-116876D02*
G03I-2640J0D01*
G01X175452Y-97124D02*
G03I-1968J0D01*
G01X186225Y-97178D02*
G03I-1971J0D01*
G01X181439Y-100556D02*
G03I-2640J0D01*
G01X174681Y-103361D02*
G03I-2640J0D01*
G01X188199D02*
G03I-2640J0D01*
G01X179841Y-79975D02*
G03I-1042J0D01*
G01X171217Y-88444D02*
G03I-1282J0D01*
G01X173123Y-92378D02*
G03I-1584J0D01*
G01X180255Y-83924D02*
G03I-1456J0D01*
G01X180669Y-88708D02*
G03I-1870J0D01*
G01X180979Y-94320D02*
G03I-2180J0D01*
G01X179433Y-76648D02*
G03I-634J0D01*
G01X191096Y-134658D02*
G03I-892J0D01*
G01X192135Y-136781D02*
G03I-631J0D01*
G01X198775Y-128635D02*
G03I-1458J0D01*
G01X195808Y-125255D02*
G03I-1869J0D01*
G01X200547Y-113952D02*
G03X203345Y-117196I7247J3422D01*
G01X192148Y-121285D02*
G03I-2180J0D01*
G01X187928Y-127802D02*
G03I-1584J0D01*
G01X189667Y-131511D02*
G03I-1283J0D01*
G01X200699Y-105836D02*
G03X200547Y-113953I8974J-4228D01*
G01X208284Y-101612D02*
G03X200698Y-105835I-219J-8531D01*
G01X192148Y-98951D02*
G03I-2180J0D01*
G01X191108Y-82727D02*
G03I-634J0D01*
G01X190184Y-85250D02*
G03I-893J0D01*
G01X195808Y-94981D02*
G03I-1869J0D01*
G01X187839Y-92457D02*
G03I-1584J0D01*
G01X189190Y-88538D02*
G03I-1283J0D01*
G01X214259Y-115661D02*
G03X213314Y-114453I-714J415D01*
G01X202049Y-108260D02*
G03X205722Y-116181I7039J-1548D01*
G01X218075Y-112869D02*
G03X219083Y-115752I4343J-99D01*
G01X208854Y-116658D02*
G03X213313Y-114452I-2485J10632D01*
G01X208470Y-118462D02*
G03X214261Y-115663I-1122J9711D01*
G01X203346Y-117195D02*
G03X208470Y-118461I4545J7394D01*
G01X205721Y-116179D02*
G03X208853Y-116659I2561J6250D01*
G01X215903Y-114020D02*
G03X219079Y-118061I6190J1597D01*
G01X215904Y-114020D02*
Y-111835D01*
G01X227413Y-112869D02*
X218074D01*
G01X214175Y-103951D02*
G03X208283Y-101613I-6403J-7542D01*
G01X213150Y-105147D02*
G03X214175Y-103951I410J686D01*
G01X213152Y-105146D02*
G03X208030Y-103430I-5122J-6786D01*
G01X208029Y-103429D02*
G03X202049Y-108259I-48J-6058D01*
G01X225189Y-111399D02*
G03X218071I-3559J159D01*
G01X218070Y-111418D02*
Y-111399D01*
G01X225188Y-111418D02*
X218070D01*
G01X227412Y-111835D02*
G03X215906I-5753J223D01*
G01X230059Y-117625D02*
Y-102034D01*
G01X230060Y-117626D02*
G03X232080I1010J239D01*
G01X226590Y-116472D02*
G03X225311Y-115210I-817J451D01*
G01X234673Y-114020D02*
G03X237849Y-118061I6190J1597D01*
G01X232081Y-102041D02*
Y-117625D01*
G01X219083Y-115753D02*
G03X225311Y-115211I2844J3371D01*
G01X219079Y-118060D02*
G03X226591Y-116473I2662J5972D01*
G01X227413Y-111835D02*
Y-112869D01*
G01X232080Y-102041D02*
G03X230060Y-102034I-1011J-236D01*
G01X225188Y-111399D02*
Y-111418D01*
G01X234675Y-114020D02*
Y-111835D01*
G01X246181D02*
G03X234675I-5753J223D01*
G01X252849Y-116771D02*
G03X254892Y-115895I-74J2994D01*
G01X236844Y-112869D02*
G03X237852Y-115752I4343J-99D01*
G01X237848Y-118060D02*
G03X245360Y-116473I2662J5972D01*
G01X245358Y-116472D02*
G03X244079Y-115210I-817J451D01*
G01X237852Y-115753D02*
G03X244080Y-115211I2844J3371D01*
G01X249566Y-115529D02*
G03X252307Y-116760I2985J2980D01*
G01Y-116761D02*
G03X252849Y-116772I366J4691D01*
G01X250282Y-118087D02*
G03X254318Y-118340I2605J9244D01*
G01X247897Y-116444D02*
G03X250283Y-118086I3752J2898D01*
G01X249568Y-115529D02*
G03X247898Y-116443I-748J-616D01*
G01X255608Y-108618D02*
G03X253612Y-107689I-3116J-4086D01*
G01X246181Y-111835D02*
Y-112869D01*
G01D02*
X236844D01*
G01X255002Y-114328D02*
G03X252723Y-112986I-3540J-3405D01*
G01X249955Y-112030D02*
G03X252723Y-112985I8208J19302D01*
G01X243957Y-111399D02*
Y-111418D01*
G01X243958Y-111399D02*
G03X236840I-3559J159D01*
G01X236841Y-111418D02*
Y-111399D01*
G01X243957Y-111418D02*
X236841D01*
G01X248537Y-109748D02*
G03X249956Y-112031I2652J66D01*
G01X248537Y-108250D02*
Y-109748D01*
G01X250179Y-106359D02*
G03X248537Y-108249I2747J-4045D01*
G01X256884Y-107368D02*
G03X250178Y-106359I-4153J-4811D01*
G01X253611Y-107689D02*
G03X251080Y-107949I-869J-3992D01*
G01X251081Y-107948D02*
G03X250837Y-110104I805J-1183D01*
G01Y-110106D02*
G03X254306Y-111513I5270J8013D01*
G01X260954Y-116041D02*
Y-107954D01*
G01X254892Y-115895D02*
G03X255001Y-114328I-764J840D01*
G01X269619Y-117484D02*
Y-106797D01*
G01X269620Y-117484D02*
G03X271926I1153J198D01*
G01X266864Y-117375D02*
G03X266002Y-116329I-764J249D01*
G01X262978Y-115462D02*
G03X266002Y-116329I2046J1428D01*
G01X260955Y-116043D02*
G03X264164Y-118351I2956J725D01*
G01X265463Y-118350D02*
X264165D01*
G01X265464Y-118352D02*
G03X266864Y-117374I-24J1525D01*
G01X256906Y-116470D02*
G03X257054Y-113728I-3143J1545D01*
G01X254317Y-118340D02*
G03X256906Y-116470I-1259J4470D01*
G01X262978Y-107954D02*
Y-115463D01*
G01X257054Y-113729D02*
G03X254307Y-111513I-3470J-1490D01*
G01X271969Y-102342D02*
G03I-1194J0D01*
G01X271926Y-106797D02*
G03X269620I-1153J-409D01*
G01X266003Y-107954D02*
X262978D01*
G01X266004Y-107955D02*
G03X266008Y-105932I-177J1012D01*
G01X262978D02*
X266008D01*
G01X262971Y-103419D02*
X262978Y-105932D01*
G01X262972Y-103418D02*
G03X260954Y-103491I-1005J-141D01*
G01Y-105932D02*
Y-103492D01*
G01X259930Y-105932D02*
X260954D01*
G01X259930D02*
G03X259981Y-107955I298J-1005D01*
G01X260954Y-107954D02*
X259982D01*
G01X255606Y-108620D02*
G03X256885Y-107367I599J667D01*
G01X290671Y-110842D02*
G03X290703Y-118351I860J-3751D01*
G01X276837Y-114305D02*
G03X278891Y-116297I4069J2141D01*
G01X274529Y-113568D02*
G03X275888Y-116443I5718J944D01*
G01X275887D02*
G03X279572Y-118352I4392J3967D01*
G01X281425Y-118350D02*
X279571D01*
G01X281425D02*
G03X284525Y-117161I0J4636D01*
G01X285201Y-116508D02*
X284524Y-117161D01*
G01X285201Y-116508D02*
G03X283966Y-115211I-695J574D01*
G01X281510Y-116675D02*
G03X283966Y-115212I-989J4453D01*
G01X278889Y-116297D02*
G03X281508Y-116677I1946J4197D01*
G01X271926Y-106797D02*
Y-117484D01*
G01X274529Y-113566D02*
Y-111839D01*
G01X276446Y-112943D02*
G03X276837Y-114305I4162J458D01*
G01X276445Y-112066D02*
Y-112943D01*
G01X283833Y-109274D02*
G03X285403Y-108106I585J852D01*
G01X285402D02*
G03X280919Y-105777I-4776J-3714D01*
G01X279541D02*
X280919D01*
G01X279540D02*
G03X274999Y-109274I1260J-6333D01*
G01X274998D02*
G03X274529Y-111839I9988J-3152D01*
G01X276849Y-109932D02*
G03X276446Y-112066I5467J-2137D01*
G01X280036Y-107542D02*
G03X276849Y-109933I664J-4205D01*
G01X282662Y-108199D02*
G03X280037Y-107539I-2313J-3650D01*
G01X283833Y-109275D02*
G03X282662Y-108202I-9277J-8949D01*
G01X294457Y-116619D02*
G03Y-112289I-51J2165D01*
G01X291853Y-116620D02*
X294456D01*
G01X291853Y-112289D02*
G03Y-116619I195J-2165D01*
G01X294165Y-118350D02*
X290701D01*
G01X294165D02*
G03X296471Y-117226I-1088J5161D01*
G01X296473Y-117625D02*
Y-117226D01*
G01X296474Y-117627D02*
G03X298494I1010J185D01*
G01X298495Y-109394D02*
Y-117625D01*
G01X301067Y-108534D02*
Y-106508D01*
G01X301615Y-108534D02*
X301067D01*
G01X301615Y-106508D02*
Y-108534D01*
G01X302461Y-106508D02*
X301615D01*
G01X302461Y-106001D02*
Y-106508D01*
G01X300223Y-106001D02*
X302461D01*
G01X300223Y-106508D02*
Y-106001D01*
G01X301067Y-106508D02*
X300223D01*
G01X305164Y-106001D02*
X304731D01*
G01X305713Y-108544D02*
X305164Y-106001D01*
G01X305171Y-108544D02*
X305713D01*
G01X304889Y-106871D02*
X305171Y-108544D01*
G01X304309D02*
X304889Y-106871D01*
G01X304086Y-108544D02*
X304309D01*
G01X303501Y-106887D02*
X304086Y-108544D01*
G01X303226D02*
X303501Y-106887D01*
G01X302698Y-108544D02*
X303226D01*
G01X303243Y-106001D02*
X302698Y-108544D01*
G01X303648Y-106001D02*
X303243D01*
G01X304192Y-107632D02*
X303648Y-106001D01*
G01X304731D02*
X304192Y-107632D01*
G01X294456Y-112288D02*
X291853D01*
G01X296473Y-110841D02*
Y-109686D01*
G01X296472Y-110841D02*
G03X292878Y-110536I-3256J-17043D01*
G01X292879Y-110535D02*
G03X290670Y-110842I280J-10112D01*
G01X298496Y-109394D02*
G03X295031Y-105933I-3962J-501D01*
G01X291563Y-105932D02*
X295031D01*
G01X291562D02*
G03X289112Y-107085I584J-4421D01*
G01Y-107086D02*
G03X289820Y-108520I585J-603D01*
G01X290987Y-107954D02*
G03X289821Y-108520I1446J-4464D01*
G01X294740Y-107954D02*
X290987D01*
G01X296473Y-109686D02*
G03X294742Y-107955I-1598J133D01*
G01X380900Y-131934D02*
X381700Y-132600D01*
X382600Y-133000D01*
X383400D01*
X384200Y-132600D01*
X384800Y-131934D01*
X385100Y-131000D01*
X384900Y-130067D01*
X384400Y-129267D01*
X383500Y-128733D01*
X382300Y-128467D01*
X381600Y-127933D01*
X381300Y-127000D01*
X381500Y-126067D01*
X382000Y-125400D01*
X382700Y-125000D01*
X383400D01*
X384100Y-125267D01*
X384700Y-125933D01*
G01X391000Y-133000D02*
X390200Y-132867D01*
X389500Y-132333D01*
X388900Y-131533D01*
X388500Y-130600D01*
X388300Y-129533D01*
Y-128467D01*
X388500Y-127400D01*
X388900Y-126467D01*
X389500Y-125667D01*
X390200Y-125133D01*
X391000Y-125000D01*
X391800Y-125133D01*
X392500Y-125667D01*
X393100Y-126467D01*
X393500Y-127400D01*
X393700Y-128467D01*
Y-129533D01*
X393500Y-130600D01*
X393100Y-131533D01*
X392500Y-132333D01*
X391800Y-132867D01*
X391000Y-133000D01*
G01X397000Y-125000D02*
Y-133000D01*
X401000D01*
G01X404800D02*
Y-125000D01*
X406800D01*
X407600Y-125400D01*
X408200Y-125933D01*
X408700Y-126733D01*
X409100Y-127667D01*
X409200Y-129000D01*
X409100Y-130333D01*
X408700Y-131267D01*
X408200Y-132067D01*
X407600Y-132600D01*
X406800Y-133000D01*
X404800D01*
G01X417000D02*
X413000D01*
Y-125000D01*
X417000D01*
G01X415400Y-128867D02*
X413000D01*
G01X421000Y-133000D02*
Y-125000D01*
X423500D01*
X424300Y-125400D01*
X424800Y-125933D01*
X425000Y-127000D01*
X424800Y-128067D01*
X424200Y-128733D01*
X423500Y-129133D01*
X421000D01*
G01X423500D02*
X425000Y-133000D01*
G01X429000D02*
Y-125000D01*
X431400D01*
X432200Y-125400D01*
X432800Y-126333D01*
X433000Y-127400D01*
X432800Y-128467D01*
X432300Y-129267D01*
X431400Y-129667D01*
X429000D01*
G01X436500Y-133000D02*
X439000Y-125000D01*
X441500Y-133000D01*
G01X440600Y-130200D02*
X437400D01*
G01X444900Y-131934D02*
X445700Y-132600D01*
X446600Y-133000D01*
X447400D01*
X448200Y-132600D01*
X448800Y-131934D01*
X449100Y-131000D01*
X448900Y-130067D01*
X448400Y-129267D01*
X447500Y-128733D01*
X446300Y-128467D01*
X445600Y-127933D01*
X445300Y-127000D01*
X445500Y-126067D01*
X446000Y-125400D01*
X446700Y-125000D01*
X447400D01*
X448100Y-125267D01*
X448700Y-125933D01*
G01X455000Y-125000D02*
Y-133000D01*
G01X452700Y-125000D02*
X457300D01*
G01X465000Y-133000D02*
X461000D01*
Y-125000D01*
X465000D01*
G01X463400Y-128867D02*
X461000D01*
G01X468000Y-135667D02*
X474000D01*
G01X479800Y-128733D02*
X480200Y-128333D01*
X480500Y-127667D01*
X480700Y-126733D01*
X480500Y-125933D01*
X480100Y-125400D01*
X479400Y-125000D01*
X476700D01*
Y-133000D01*
X480000D01*
X480700Y-132467D01*
X481100Y-131667D01*
X481300Y-130733D01*
X481100Y-129800D01*
X480500Y-129000D01*
X479800Y-128733D01*
X476700D01*
G01X487000Y-133000D02*
X486200Y-132867D01*
X485500Y-132333D01*
X484900Y-131533D01*
X484500Y-130600D01*
X484300Y-129533D01*
Y-128467D01*
X484500Y-127400D01*
X484900Y-126467D01*
X485500Y-125667D01*
X486200Y-125133D01*
X487000Y-125000D01*
X487800Y-125133D01*
X488500Y-125667D01*
X489100Y-126467D01*
X489500Y-127400D01*
X489700Y-128467D01*
Y-129533D01*
X489500Y-130600D01*
X489100Y-131533D01*
X488500Y-132333D01*
X487800Y-132867D01*
X487000Y-133000D01*
G01X495000Y-125000D02*
Y-133000D01*
G01X492700Y-125000D02*
X497300D01*
G54D13*
X109000Y351200D03*
Y345800D03*
X132000Y354800D03*
Y360200D03*
X226000Y67700D03*
Y62300D03*
X284500Y216800D03*
Y222200D03*
X318500Y285300D03*
Y290700D03*
X377000Y86300D03*
Y91700D03*
X427000Y77800D03*
Y83200D03*
X570000Y231800D03*
Y237200D03*
G54D22*
X393098Y152847D03*
X389160Y148910D03*
X393098D03*
Y164658D03*
Y176470D03*
Y172532D03*
Y184343D03*
Y200091D03*
X393097Y204028D03*
X393098Y207964D03*
Y211902D03*
X389160Y215839D03*
X393098D03*
X397035Y144973D03*
X404910Y141036D03*
Y137098D03*
X400973Y144972D03*
X397036Y152847D03*
X400973Y160720D03*
Y164658D03*
X397035Y148911D03*
X397036Y164658D03*
X400973Y148910D03*
X408847Y160721D03*
X404910Y164659D03*
Y160721D03*
X408847Y156784D03*
X400973Y156785D03*
Y152847D03*
X404909Y148910D03*
X408847D03*
X400972Y180406D03*
X404910D03*
X404909Y168595D03*
X408847D03*
X404910Y196155D03*
Y192217D03*
X397035D03*
X400973D03*
X408846Y196154D03*
X397036Y184343D03*
Y200091D03*
X397035Y204028D03*
X420658Y144973D03*
Y141035D03*
Y160720D03*
Y164658D03*
X412783Y148910D03*
X416721D03*
X412783Y152847D03*
X416721D03*
X420658Y148909D03*
Y152847D03*
X424595Y164659D03*
Y160721D03*
X416721Y164658D03*
X424596Y156784D03*
X420658D03*
X416721Y156783D03*
Y160721D03*
X412784Y164657D03*
X412785Y160721D03*
Y156784D03*
X420657Y180406D03*
X424595D03*
X416721Y168596D03*
X420657Y168595D03*
X424595D03*
X412784D03*
X420658Y188281D03*
Y184343D03*
X416721Y196154D03*
X412784D03*
X424595Y215840D03*
Y211902D03*
X416721Y200092D03*
X416722Y204028D03*
X412784D03*
X440343Y137099D03*
Y133161D03*
X444280Y141035D03*
Y144973D03*
X436406D03*
X430900Y144531D03*
X440343Y156783D03*
Y160721D03*
X444280Y164658D03*
Y160722D03*
Y156784D03*
X440343Y164657D03*
X436406Y164659D03*
Y160721D03*
Y148911D03*
Y152846D03*
Y156784D03*
X430900Y148469D03*
X444280Y168595D03*
X440343D03*
X440344Y180406D03*
X436406D03*
X444280Y180405D03*
X440342Y192217D03*
X444280D03*
X431006Y193718D03*
Y189780D03*
X444280Y184343D03*
X440343Y215839D03*
Y219777D03*
X463965Y129224D03*
X460027D03*
X452154Y141035D03*
Y137097D03*
X456090Y141035D03*
X460028D03*
X452155Y144973D03*
X448217D03*
X460028Y156785D03*
Y152847D03*
X452154Y164657D03*
X448217Y156783D03*
Y160721D03*
X448218Y164658D03*
X463964Y156784D03*
X448218Y168595D03*
X452154D03*
X460027D03*
X463965D03*
Y180406D03*
X452154D03*
X448217Y180405D03*
X463966Y196154D03*
X460028D03*
X463966Y192217D03*
X460028D03*
X463965Y188281D03*
Y184343D03*
X448216Y196154D03*
Y192216D03*
X452154Y184344D03*
X448217Y184343D03*
X456090D03*
X460028D03*
X460029Y188280D03*
X456091D03*
X448216Y207965D03*
X452154D03*
X476666Y138867D03*
Y142805D03*
X467902Y156784D03*
X467903Y180406D03*
X467901Y168595D03*
X471839D03*
X467902Y188281D03*
Y184343D03*
Y215840D03*
Y211902D03*
X475777Y200091D03*
X471839D03*
Y215840D03*
Y211902D03*
X471840Y207965D03*
X467902D03*
G54D14*
X147200Y409000D03*
X141800D03*
X351600Y388700D03*
X357000D03*
X361800Y139500D03*
X367200D03*
G54D23*
X398250Y232500D03*
X408750D03*
G54D24*
X531600Y351999D03*
Y369401D03*
G54D15*
X162650Y403100D03*
X163550D03*
X337250Y394700D03*
X336350D03*
G54D16*
X174850Y338800D03*
Y353800D03*
Y348800D03*
Y343800D03*
X196950Y338800D03*
Y343800D03*
Y348800D03*
Y353800D03*
G54D25*
X564500Y233457D03*
Y235543D03*
G54D17*
X180700Y413000D03*
X187300D03*
X306800Y194500D03*
X300200D03*
X373200Y106000D03*
X367800Y223000D03*
X361200D03*
X379800Y106000D03*
X413400Y285500D03*
X420000D03*
X413400Y293600D03*
X420000D03*
X493300Y126300D03*
X499900D03*
X508000Y245400D03*
X501400D03*
X546100Y320600D03*
X546500Y336400D03*
Y328800D03*
Y344100D03*
X568700Y199000D03*
X552700Y320600D03*
X553100Y336400D03*
Y328800D03*
Y344100D03*
X575300Y199000D03*
G54D26*
X564000Y217450D03*
Y216550D03*
G54D27*
X567550Y263750D03*
Y272450D03*
X567050Y300950D03*
Y292250D03*
X575050Y272450D03*
X574550Y300950D03*
G54D18*
X246559Y228700D03*
X241441Y219300D03*
Y228700D03*
X244000Y219300D03*
X246559D03*
G54D28*
X574250Y263750D03*
X573750Y292250D03*
G54D19*
X269000Y219350D03*
X265260D03*
Y230650D03*
X272740Y219350D03*
Y230650D03*
G54D29*
G01X136000Y-65500D02*
Y-158000D01*
X506000D01*
Y-65500D01*
X136000D01*
G01X316000D02*
Y-158000D01*
M02*
